# S9S_MB_2U (Grand Teton) — schematic netlist excerpt (pin names and nets, part order shuffled) for the footprints in the layout excerpt that follows; sources: Cadence DE-HDL packaged netlist, KiCad conversion of 03242023_DA0F0TMBIJ0_F0T_Motherboard_J_brd_V01_OCP.brd

PR97  Q_RES  2.2 1% CHIP  pkg 0402LF  page 276 : A = PVCCFA_EHV_CPU0_PVCC ; B = PVCCFA_EHV_CPU0_VDD1
R737  Q_RES  0 5% CHIP  pkg 0402LF  page 133 : A = FM_CPU1_SKTOCC_LVT3_N ; B = FM_CPU1_SKTOCC_N

(kicad_pcb
	(version 20260206)
	(generator "pcbnew")
	(generator_version "10.0")
	(general
		(thickness 1.6)
		(legacy_teardrops no)
	)
	(paper "A4")
	(title_block
		(title "03242023_DA0F0TMBIJ0_F0T_Motherboard_J_brd_V01_OCP.brd")
		(comment 1 "Grand Teton / footprints 5934-5935 of 6105")
	)
	(layers
		(0 "F.Cu" signal "TOP")
		(4 "In1.Cu" signal "GND")
		(6 "In2.Cu" signal "IN1")
		(8 "In3.Cu" signal "GND1")
		(10 "In4.Cu" signal "IN2")
		(12 "In5.Cu" signal "GND2")
		(14 "In6.Cu" signal "IN3")
		(16 "In7.Cu" signal "GND3")
		(18 "In8.Cu" signal "VCC")
		(20 "In9.Cu" signal "VCC1")
		(22 "In10.Cu" signal "GND4")
		(24 "In11.Cu" signal "IN4")
		(26 "In12.Cu" signal "GND5")
		(28 "In13.Cu" signal "IN5")
		(30 "In14.Cu" signal "GND6")
		(32 "In15.Cu" signal "IN6")
		(34 "In16.Cu" signal "GND7")
		(2 "B.Cu" signal "BOTTOM")
		(9 "F.Adhes" user "F.Adhesive")
		(11 "B.Adhes" user "B.Adhesive")
		(13 "F.Paste" user "Package Geometry/Pastemask Top")
		(15 "B.Paste" user "Package Geometry/Pastemask Bottom")
		(5 "F.SilkS" user "Ref Des/Silkscreen Top")
		(7 "B.SilkS" user "Ref Des/Silkscreen Bottom")
		(1 "F.Mask" user "Board Geometry/Soldermask Top")
		(3 "B.Mask" user "Board Geometry/Soldermask Bottom")
		(17 "Dwgs.User" user "User.Drawings")
		(19 "Cmts.User" user "User.Comments")
		(21 "Eco1.User" user "User.Eco1")
		(23 "Eco2.User" user "User.Eco2")
		(25 "Edge.Cuts" user "Board Geometry/Outline")
		(27 "Margin" user)
		(31 "F.CrtYd" user "Package Geometry/Place Bound Top")
		(29 "B.CrtYd" user "Package Geometry/Place Bound Bottom")
		(35 "F.Fab" user "Ref Des/Assembly Top")
		(33 "B.Fab" user "Ref Des/Assembly Bottom")
	)
	(footprint ""
		(layer "B.Cu")
		(at 201.961496 -194.054984)
		(property "Reference" "R737"
			(at 0 0 0)
			(layer "B.SilkS")
			(hide yes)
			(effects
				(font
					(size 1.27 1.27)
				)
				(justify mirror)
			)
		)
		(property "Value" ""
			(at 0 0 0)
			(layer "B.Fab")
			(effects
				(font
					(size 1.27 1.27)
				)
				(justify mirror)
			)
		)
		(duplicate_pad_numbers_are_jumpers no)
		(fp_line
			(start -0.7874 -0.4064)
			(end -0.7874 0.4064)
			(stroke
				(width 0.1524)
				(type default)
			)
			(layer "B.SilkS")
		)
		(fp_line
			(start -0.7874 0.4064)
			(end 0.7874 0.4064)
			(stroke
				(width 0.1524)
				(type default)
			)
			(layer "B.SilkS")
		)
		(fp_line
			(start 0.7874 -0.4064)
			(end -0.7874 -0.4064)
			(stroke
				(width 0.1524)
				(type default)
			)
			(layer "B.SilkS")
		)
		(fp_line
			(start 0.7874 0.4064)
			(end 0.7874 -0.4064)
			(stroke
				(width 0.1524)
				(type default)
			)
			(layer "B.SilkS")
		)
		(fp_line
			(start -0.67945 -0.3048)
			(end -0.67945 0.3048)
			(stroke
				(width 0.1)
				(type default)
			)
			(layer "B.Fab")
		)
		(fp_line
			(start -0.67945 0.3048)
			(end -0.120396 0.3048)
			(stroke
				(width 0.1)
				(type default)
			)
			(layer "B.Fab")
		)
		(fp_line
			(start -0.12065 -0.3048)
			(end -0.67945 -0.3048)
			(stroke
				(width 0.1)
				(type default)
			)
			(layer "B.Fab")
		)
		(fp_line
			(start -0.12065 -0.2794)
			(end -0.12065 -0.3048)
			(stroke
				(width 0.1)
				(type default)
			)
			(layer "B.Fab")
		)
		(fp_line
			(start -0.120396 0.2794)
			(end 0.12065 0.2794)
			(stroke
				(width 0.1)
				(type default)
			)
			(layer "B.Fab")
		)
		(fp_line
			(start -0.120396 0.3048)
			(end -0.120396 0.2794)
			(stroke
				(width 0.1)
				(type default)
			)
			(layer "B.Fab")
		)
		(fp_line
			(start 0.12065 -0.305054)
			(end 0.12065 -0.2794)
			(stroke
				(width 0.1)
				(type default)
			)
			(layer "B.Fab")
		)
		(fp_line
			(start 0.12065 -0.2794)
			(end -0.12065 -0.2794)
			(stroke
				(width 0.1)
				(type default)
			)
			(layer "B.Fab")
		)
		(fp_line
			(start 0.12065 0.2794)
			(end 0.12065 0.3048)
			(stroke
				(width 0.1)
				(type default)
			)
			(layer "B.Fab")
		)
		(fp_line
			(start 0.12065 0.3048)
			(end 0.67945 0.3048)
			(stroke
				(width 0.1)
				(type default)
			)
			(layer "B.Fab")
		)
		(fp_line
			(start 0.67945 -0.305054)
			(end 0.12065 -0.305054)
			(stroke
				(width 0.1)
				(type default)
			)
			(layer "B.Fab")
		)
		(fp_line
			(start 0.67945 0.3048)
			(end 0.67945 -0.305054)
			(stroke
				(width 0.1)
				(type default)
			)
			(layer "B.Fab")
		)
		(pad "1" smd circle
			(at 0.40005 0 180)
			(size 0 0)
			(layers "B.Cu" "B.Mask" "B.Paste")
			(net "FM_CPU1_SKTOCC_LVT3_N")
		)
		(pad "2" smd circle
			(at -0.40005 0 180)
			(size 0 0)
			(layers "B.Cu" "B.Mask" "B.Paste")
			(net "FM_CPU1_SKTOCC_N")
		)
	)
	(footprint ""
		(layer "B.Cu")
		(at 419.91788 -156.632148 -90)
		(property "Reference" "PR97"
			(at 0 0 90)
			(layer "B.SilkS")
			(hide yes)
			(effects
				(font
					(size 1.27 1.27)
				)
				(justify mirror)
			)
		)
		(property "Value" ""
			(at 0 0 90)
			(layer "B.Fab")
			(effects
				(font
					(size 1.27 1.27)
				)
				(justify mirror)
			)
		)
		(duplicate_pad_numbers_are_jumpers no)
		(fp_line
			(start -0.7874 0.4064)
			(end 0.7874 0.4064)
			(stroke
				(width 0.1524)
				(type default)
			)
			(layer "B.SilkS")
		)
		(fp_line
			(start 0.7874 0.4064)
			(end 0.7874 -0.4064)
			(stroke
				(width 0.1524)
				(type default)
			)
			(layer "B.SilkS")
		)
		(fp_line
			(start -0.7874 -0.4064)
			(end -0.7874 0.4064)
			(stroke
				(width 0.1524)
				(type default)
			)
			(layer "B.SilkS")
		)
		(fp_line
			(start 0.7874 -0.4064)
			(end -0.7874 -0.4064)
			(stroke
				(width 0.1524)
				(type default)
			)
			(layer "B.SilkS")
		)
		(fp_line
			(start -0.67945 0.3048)
			(end -0.120396 0.3048)
			(stroke
				(width 0.1)
				(type default)
			)
			(layer "B.Fab")
		)
		(fp_line
			(start -0.120396 0.3048)
			(end -0.120396 0.2794)
			(stroke
				(width 0.1)
				(type default)
			)
			(layer "B.Fab")
		)
		(fp_line
			(start 0.12065 0.3048)
			(end 0.67945 0.3048)
			(stroke
				(width 0.1)
				(type default)
			)
			(layer "B.Fab")
		)
		(fp_line
			(start 0.67945 0.3048)
			(end 0.67945 -0.305054)
			(stroke
				(width 0.1)
				(type default)
			)
			(layer "B.Fab")
		)
		(fp_line
			(start -0.120396 0.2794)
			(end 0.12065 0.2794)
			(stroke
				(width 0.1)
				(type default)
			)
			(layer "B.Fab")
		)
		(fp_line
			(start 0.12065 0.2794)
			(end 0.12065 0.3048)
			(stroke
				(width 0.1)
				(type default)
			)
			(layer "B.Fab")
		)
		(fp_line
			(start -0.12065 -0.2794)
			(end -0.12065 -0.3048)
			(stroke
				(width 0.1)
				(type default)
			)
			(layer "B.Fab")
		)
		(fp_line
			(start 0.12065 -0.2794)
			(end -0.12065 -0.2794)
			(stroke
				(width 0.1)
				(type default)
			)
			(layer "B.Fab")
		)
		(fp_line
			(start -0.67945 -0.3048)
			(end -0.67945 0.3048)
			(stroke
				(width 0.1)
				(type default)
			)
			(layer "B.Fab")
		)
		(fp_line
			(start -0.12065 -0.3048)
			(end -0.67945 -0.3048)
			(stroke
				(width 0.1)
				(type default)
			)
			(layer "B.Fab")
		)
		(fp_line
			(start 0.12065 -0.305054)
			(end 0.12065 -0.2794)
			(stroke
				(width 0.1)
				(type default)
			)
			(layer "B.Fab")
		)
		(fp_line
			(start 0.67945 -0.305054)
			(end 0.12065 -0.305054)
			(stroke
				(width 0.1)
				(type default)
			)
			(layer "B.Fab")
		)
		(pad "1" smd circle
			(at 0.40005 0 90)
			(size 0 0)
			(layers "B.Cu" "B.Mask" "B.Paste")
			(net "PVCCFA_EHV_CPU0_PVCC")
		)
		(pad "2" smd circle
			(at -0.40005 0 90)
			(size 0 0)
			(layers "B.Cu" "B.Mask" "B.Paste")
			(net "PVCCFA_EHV_CPU0_VDD1")
		)
	)
)
